# SCM (Grand Teton) — schematic netlist excerpt (pin names and nets, part order shuffled) for the footprints in the layout excerpt that follows; sources: Cadence DE-HDL packaged netlist, KiCad conversion of 12092022_DA0F0TMDCD0_F0T_Management_Board_D_brd_V3_OCP.brd

R553  Q_RES  33.2 1% CHIP  pkg 0402LF  page 21 : A = SPI_BMC_CS0_FLASH_R_N ; B = SPI_BMC_BOOT_CS0_R_N
R497  Q_RES  10K 1% CHIP  pkg 0402LF  page 46 : A = P3V3_AUX ; B = IRQ_PCH_TPM_SPI_N

(kicad_pcb
	(version 20260206)
	(generator "pcbnew")
	(generator_version "10.0")
	(general
		(thickness 1.6)
		(legacy_teardrops no)
	)
	(paper "A4")
	(title_block
		(title "12092022_DA0F0TMDCD0_F0T_Management_Board_D_brd_V3_OCP.brd")
		(comment 1 "Grand Teton / footprints 27-28 of 1440")
	)
	(layers
		(0 "F.Cu" signal "TOP")
		(4 "In1.Cu" signal "GND")
		(6 "In2.Cu" signal "IN1")
		(8 "In3.Cu" signal "GND1")
		(10 "In4.Cu" signal "IN2")
		(12 "In5.Cu" signal "VCC")
		(14 "In6.Cu" signal "VCC1")
		(16 "In7.Cu" signal "IN3")
		(18 "In8.Cu" signal "GND2")
		(20 "In9.Cu" signal "IN4")
		(22 "In10.Cu" signal "GND3")
		(2 "B.Cu" signal "BOTTOM")
		(9 "F.Adhes" user "F.Adhesive")
		(11 "B.Adhes" user "B.Adhesive")
		(13 "F.Paste" user "Package Geometry/Pastemask Top")
		(15 "B.Paste" user "Package Geometry/Pastemask Bottom")
		(5 "F.SilkS" user "Ref Des/Silkscreen Top")
		(7 "B.SilkS" user "Ref Des/Silkscreen Bottom")
		(1 "F.Mask" user "Board Geometry/Soldermask Top")
		(3 "B.Mask" user "Board Geometry/Soldermask Bottom")
		(17 "Dwgs.User" user "User.Drawings")
		(19 "Cmts.User" user "User.Comments")
		(21 "Eco1.User" user "User.Eco1")
		(23 "Eco2.User" user "User.Eco2")
		(25 "Edge.Cuts" user "Board Geometry/Outline")
		(27 "Margin" user)
		(31 "F.CrtYd" user "Package Geometry/Place Bound Top")
		(29 "B.CrtYd" user "Package Geometry/Place Bound Bottom")
		(35 "F.Fab" user "Ref Des/Assembly Top")
		(33 "B.Fab" user "Ref Des/Assembly Bottom")
	)
	(footprint ""
		(layer "F.Cu")
		(at 56.5912 -95.95485 -90)
		(property "Reference" "R497"
			(at 0 0 270)
			(layer "F.SilkS")
			(hide yes)
			(effects
				(font
					(size 1.27 1.27)
				)
			)
		)
		(property "Value" ""
			(at 0 0 270)
			(layer "F.Fab")
			(effects
				(font
					(size 1.27 1.27)
				)
			)
		)
		(duplicate_pad_numbers_are_jumpers no)
		(fp_line
			(start -0.7874 0.4064)
			(end -0.7874 -0.4064)
			(stroke
				(width 0.1524)
				(type default)
			)
			(layer "F.SilkS")
		)
		(fp_line
			(start 0.7874 0.4064)
			(end -0.7874 0.4064)
			(stroke
				(width 0.1524)
				(type default)
			)
			(layer "F.SilkS")
		)
		(fp_line
			(start -0.7874 -0.4064)
			(end 0.7874 -0.4064)
			(stroke
				(width 0.1524)
				(type default)
			)
			(layer "F.SilkS")
		)
		(fp_line
			(start 0.7874 -0.4064)
			(end 0.7874 0.4064)
			(stroke
				(width 0.1524)
				(type default)
			)
			(layer "F.SilkS")
		)
		(fp_line
			(start -0.67945 0.3048)
			(end -0.67945 -0.305054)
			(stroke
				(width 0.1)
				(type default)
			)
			(layer "F.Fab")
		)
		(fp_line
			(start -0.12065 0.3048)
			(end -0.67945 0.3048)
			(stroke
				(width 0.1)
				(type default)
			)
			(layer "F.Fab")
		)
		(fp_line
			(start 0.120396 0.3048)
			(end 0.120396 0.2794)
			(stroke
				(width 0.1)
				(type default)
			)
			(layer "F.Fab")
		)
		(fp_line
			(start 0.67945 0.3048)
			(end 0.120396 0.3048)
			(stroke
				(width 0.1)
				(type default)
			)
			(layer "F.Fab")
		)
		(fp_line
			(start -0.12065 0.2794)
			(end -0.12065 0.3048)
			(stroke
				(width 0.1)
				(type default)
			)
			(layer "F.Fab")
		)
		(fp_line
			(start 0.120396 0.2794)
			(end -0.12065 0.2794)
			(stroke
				(width 0.1)
				(type default)
			)
			(layer "F.Fab")
		)
		(fp_line
			(start -0.12065 -0.2794)
			(end 0.12065 -0.2794)
			(stroke
				(width 0.1)
				(type default)
			)
			(layer "F.Fab")
		)
		(fp_line
			(start 0.12065 -0.2794)
			(end 0.12065 -0.3048)
			(stroke
				(width 0.1)
				(type default)
			)
			(layer "F.Fab")
		)
		(fp_line
			(start 0.12065 -0.3048)
			(end 0.67945 -0.3048)
			(stroke
				(width 0.1)
				(type default)
			)
			(layer "F.Fab")
		)
		(fp_line
			(start 0.67945 -0.3048)
			(end 0.67945 0.3048)
			(stroke
				(width 0.1)
				(type default)
			)
			(layer "F.Fab")
		)
		(fp_line
			(start -0.67945 -0.305054)
			(end -0.12065 -0.305054)
			(stroke
				(width 0.1)
				(type default)
			)
			(layer "F.Fab")
		)
		(fp_line
			(start -0.12065 -0.305054)
			(end -0.12065 -0.2794)
			(stroke
				(width 0.1)
				(type default)
			)
			(layer "F.Fab")
		)
		(pad "1" smd circle
			(at -0.40005 0 270)
			(size 0 0)
			(layers "F.Cu" "F.Mask" "F.Paste")
			(net "P3V3_AUX")
		)
		(pad "2" smd circle
			(at 0.40005 0 270)
			(size 0 0)
			(layers "F.Cu" "F.Mask" "F.Paste")
			(net "IRQ_PCH_TPM_SPI_N")
		)
	)
	(footprint ""
		(layer "F.Cu")
		(at 41.9608 -81.026 90)
		(property "Reference" "R553"
			(at 0 0 90)
			(layer "F.SilkS")
			(hide yes)
			(effects
				(font
					(size 1.27 1.27)
				)
			)
		)
		(property "Value" ""
			(at 0 0 90)
			(layer "F.Fab")
			(effects
				(font
					(size 1.27 1.27)
				)
			)
		)
		(duplicate_pad_numbers_are_jumpers no)
		(fp_line
			(start 0.7874 -0.4064)
			(end 0.7874 0.4064)
			(stroke
				(width 0.1524)
				(type default)
			)
			(layer "F.SilkS")
		)
		(fp_line
			(start -0.7874 -0.4064)
			(end 0.7874 -0.4064)
			(stroke
				(width 0.1524)
				(type default)
			)
			(layer "F.SilkS")
		)
		(fp_line
			(start 0.7874 0.4064)
			(end -0.7874 0.4064)
			(stroke
				(width 0.1524)
				(type default)
			)
			(layer "F.SilkS")
		)
		(fp_line
			(start -0.7874 0.4064)
			(end -0.7874 -0.4064)
			(stroke
				(width 0.1524)
				(type default)
			)
			(layer "F.SilkS")
		)
		(fp_line
			(start -0.12065 -0.305054)
			(end -0.12065 -0.2794)
			(stroke
				(width 0.1)
				(type default)
			)
			(layer "F.Fab")
		)
		(fp_line
			(start -0.67945 -0.305054)
			(end -0.12065 -0.305054)
			(stroke
				(width 0.1)
				(type default)
			)
			(layer "F.Fab")
		)
		(fp_line
			(start 0.67945 -0.3048)
			(end 0.67945 0.3048)
			(stroke
				(width 0.1)
				(type default)
			)
			(layer "F.Fab")
		)
		(fp_line
			(start 0.12065 -0.3048)
			(end 0.67945 -0.3048)
			(stroke
				(width 0.1)
				(type default)
			)
			(layer "F.Fab")
		)
		(fp_line
			(start 0.12065 -0.2794)
			(end 0.12065 -0.3048)
			(stroke
				(width 0.1)
				(type default)
			)
			(layer "F.Fab")
		)
		(fp_line
			(start -0.12065 -0.2794)
			(end 0.12065 -0.2794)
			(stroke
				(width 0.1)
				(type default)
			)
			(layer "F.Fab")
		)
		(fp_line
			(start 0.120396 0.2794)
			(end -0.12065 0.2794)
			(stroke
				(width 0.1)
				(type default)
			)
			(layer "F.Fab")
		)
		(fp_line
			(start -0.12065 0.2794)
			(end -0.12065 0.3048)
			(stroke
				(width 0.1)
				(type default)
			)
			(layer "F.Fab")
		)
		(fp_line
			(start 0.67945 0.3048)
			(end 0.120396 0.3048)
			(stroke
				(width 0.1)
				(type default)
			)
			(layer "F.Fab")
		)
		(fp_line
			(start 0.120396 0.3048)
			(end 0.120396 0.2794)
			(stroke
				(width 0.1)
				(type default)
			)
			(layer "F.Fab")
		)
		(fp_line
			(start -0.12065 0.3048)
			(end -0.67945 0.3048)
			(stroke
				(width 0.1)
				(type default)
			)
			(layer "F.Fab")
		)
		(fp_line
			(start -0.67945 0.3048)
			(end -0.67945 -0.305054)
			(stroke
				(width 0.1)
				(type default)
			)
			(layer "F.Fab")
		)
		(pad "1" smd circle
			(at -0.40005 0 90)
			(size 0 0)
			(layers "F.Cu" "F.Mask" "F.Paste")
			(net "SPI_BMC_CS0_FLASH_R_N")
		)
		(pad "2" smd circle
			(at 0.40005 0 90)
			(size 0 0)
			(layers "F.Cu" "F.Mask" "F.Paste")
			(net "SPI_BMC_BOOT_CS0_R_N")
		)
	)
)
